;LEADER: 12 
;HEADER: 
;CODE  : ASCII 
;FILE  : 9324_DA0F0TMBIJ0_F0T_Motherboard_J_v01_20230324_0910-bd-18-17.drl for backdrilling ... from layer BOTTOM to layer GND7
;DESIGN: 9324_DA0F0TMBIJ0_F0T_Motherboard_J_v01_20230324_0910.brd
;MUST-NOT-CUT-LAYER = IN6,  MAX_DRILL_DEPTH = 9.30 MILS,  MFG_STUB_LENGTH = 0.00 MILS
;   BackdrillSize 1. = 15.700000 Tolerance = +0.000000/-0.000000 NON_PLATED MILS Quantity = 128
;   BackdrillSize 2. = 17.700000 Tolerance = +0.000000/-0.000000 NON_PLATED MILS Quantity = 162
;   BackdrillSize 3. = 21.870000 Tolerance = +0.000000/-0.000000 NON_PLATED MILS Quantity = 6
%
G90
X0369229Y0883423
X0361829Y0883423
X0354429Y0883423
X0371078Y0880219
X0365529Y0883423
X0363678Y0880219
X0358129Y0883423
X0356278Y0880219
X0367378Y0886627
X0359978Y0886627
X0389578Y0886627
X0382178Y0886627
X0374778Y0886627
X0411778Y0886627
X0404378Y0886627
X0396978Y0886627
X0384029Y0883423
X0376629Y0883423
X0406229Y0883423
X0398829Y0883423
X0391429Y0883423
X0387729Y0883423
X0385878Y0880219
X0380329Y0883423
X0378478Y0880219
X0372929Y0883423
X0409929Y0883423
X0408078Y0880219
X0402529Y0883423
X0400678Y0880219
X0395129Y0883423
X0393278Y0880219
X0502429Y0883423
X0495029Y0883423
X0487629Y0883423
X0480229Y0883423
X0524629Y0883423
X0517229Y0883423
X0509829Y0883423
X0472829Y0883423
X0506129Y0883423
X0504278Y0880219
X0498729Y0883423
X0496878Y0880219
X0491329Y0883423
X0489478Y0880219
X0483929Y0883423
X0482078Y0880219
X0476529Y0883423
X0528329Y0883423
X0526479Y0880219
X0520929Y0883423
X0519078Y0880219
X0513529Y0883423
X0511678Y0880219
X0474678Y0880219
X0507978Y0886627
X0500578Y0886627
X0493178Y0886627
X0485778Y0886627
X0478378Y0886627
X0530179Y0886627
X0522778Y0886627
X0515378Y0886627
X1360171Y0883423
X1352771Y0883423
X1345371Y0883423
X1337971Y0883423
X1367571Y0883423
X1330571Y0883423
X1363871Y0883423
X1362020Y0880219
X1356471Y0883423
X1354620Y0880219
X1349071Y0883423
X1347220Y0880219
X1341671Y0883423
X1339820Y0880219
X1334271Y0883423
X1371271Y0883423
X1369420Y0880219
X1332420Y0880219
X1365720Y0886627
X1358320Y0886627
X1350920Y0886627
X1343520Y0886627
X1336120Y0886627
X1469320Y0886627
X1461920Y0886627
X1454520Y0886627
X1387920Y0886627
X1380520Y0886627
X1373120Y0886627
X1471171Y0883423
X1463771Y0883423
X1456371Y0883423
X1448971Y0883423
X1467471Y0883423
X1465620Y0880219
X1460071Y0883423
X1458220Y0880219
X1452671Y0883423
X1450820Y0880219
X1382371Y0883423
X1374971Y0883423
X1386071Y0883423
X1384220Y0880219
X1378671Y0883423
X1376820Y0880219
X1478571Y0883423
X1500771Y0883423
X1493371Y0883423
X1485971Y0883423
X1482271Y0883423
X1480420Y0880219
X1474871Y0883423
X1473020Y0880219
X1504471Y0883423
X1502621Y0880219
X1497071Y0883423
X1495220Y0880219
X1489671Y0883423
X1487820Y0880219
X1484120Y0886627
X1476720Y0886627
X1506321Y0886627
X1498920Y0886627
X1491520Y0886627
M00
X0076369Y1507456
X0168110Y1518014
X0079769Y1507456
X0164710Y1518014
X0149712Y1569525
X0105651Y1576504
X0102251Y1576504
X0146312Y1569525
X0092664Y1507611
X0148938Y1517374
X0089264Y1507611
X0145538Y1517374
X0075922Y1562374
X0075922Y1558974
X0264657Y1578182
X0192297Y1578182
X0204357Y1578182
X0216417Y1578182
X0228477Y1578182
X0240537Y1578182
X0252597Y1578182
X0261257Y1578182
X0188897Y1578182
X0200957Y1578182
X0213017Y1578182
X0225077Y1578182
X0237137Y1578182
X0249197Y1578182
X0276717Y1578182
X0288777Y1578182
X0300837Y1578182
X0312897Y1578182
X0324957Y1578182
X0337017Y1578182
X0349077Y1578182
X0361137Y1578182
X0273317Y1578182
X0285377Y1578182
X0297437Y1578182
X0309497Y1578182
X0321557Y1578182
X0333617Y1578182
X0345677Y1578182
X0357737Y1578182
X0369797Y1578182
X0402590Y1618952
X0405990Y1618952
X0423180Y1602802
X0419780Y1602802
X0373197Y1578182
X0545411Y1578182
X0557471Y1578182
X0569531Y1578182
X0473051Y1578182
X0485111Y1578182
X0497171Y1578182
X0509231Y1578182
X0521291Y1578182
X0533351Y1578182
X0548811Y1578182
X0560871Y1578182
X0476451Y1578182
X0488511Y1578182
X0500571Y1578182
X0512631Y1578182
X0524691Y1578182
X0536751Y1578182
X0581591Y1578182
X0593651Y1578182
X0605711Y1578182
X0617771Y1578182
X0629831Y1578182
X0641891Y1578182
X0653951Y1578182
X0572931Y1578182
X0584991Y1578182
X0597051Y1578182
X0609111Y1578182
X0621171Y1578182
X0633231Y1578182
X0645291Y1578182
X0657351Y1578182
X0704770Y0179599
X0704770Y0182999
X0704770Y0191410
X0704770Y0203221
X0704770Y0215032
X0704770Y0194810
X0704770Y0206621
X0704770Y0218432
X1205472Y1602380
X1217532Y1602380
X1229592Y1602380
X1241652Y1602380
X1253712Y1602380
X1265772Y1602380
X1202072Y1602380
X1214132Y1602380
X1226192Y1602380
X1238252Y1602380
X1250312Y1602380
X1262372Y1602380
X1277832Y1602380
X1289892Y1602380
X1301952Y1602380
X1314012Y1602380
X1326072Y1602380
X1338132Y1602380
X1350192Y1602380
X1362252Y1602380
X1274432Y1602380
X1286492Y1602380
X1298552Y1602380
X1310612Y1602380
X1322672Y1602380
X1334732Y1602380
X1346792Y1602380
X1358852Y1602380
X1370912Y1602380
X1374312Y1602380
X1386372Y1602380
X1382972Y1602380
X1465695Y1578182
X1462295Y1578182
X1426510Y0184263
X1417350Y0184263
X1408229Y0184263
X1423110Y0184263
X1413950Y0184263
X1404829Y0184263
X1404741Y0177159
X1401341Y0177159
X1534655Y1578182
X1546715Y1578182
X1558775Y1578182
X1570835Y1578182
X1474355Y1578182
X1486415Y1578182
X1498475Y1578182
X1510535Y1578182
X1522595Y1578182
X1538055Y1578182
X1550115Y1578182
X1562175Y1578182
X1477755Y1578182
X1489815Y1578182
X1501875Y1578182
X1513935Y1578182
X1525995Y1578182
X1582895Y1578182
X1594955Y1578182
X1607015Y1578182
X1619075Y1578182
X1631135Y1578182
X1643195Y1578182
X1574235Y1578182
X1586295Y1578182
X1598355Y1578182
X1610415Y1578182
X1622475Y1578182
X1634535Y1578182
X1646595Y1578182
M00
X0270276Y1657834
X0270276Y1653110
X0286024Y1672007
X0286024Y1667283
X0286024Y1657834
X0286024Y1653110
M30
